(kicad_pcb
	(version 20260206)
	(generator "pcbnew")
	(generator_version "10.0")
	(general
		(thickness 1.6)
		(legacy_teardrops no)
	)
	(paper "A4")
	(title_block
		(title "01162023_DA0F0TEBIF0_F0T_Expander_BD_F_brd_V02_OCP.brd")
		(comment 1 "Grand Teton / footprints 3217-3221 of 9728")
	)
	(layers
		(0 "F.Cu" signal "TOP")
		(4 "In1.Cu" signal "GND")
		(6 "In2.Cu" signal "VCC")
		(8 "In3.Cu" signal "VCC1")
		(10 "In4.Cu" signal "GND1")
		(12 "In5.Cu" signal "IN1")
		(14 "In6.Cu" signal "GND2")
		(16 "In7.Cu" signal "IN2")
		(18 "In8.Cu" signal "GND3")
		(20 "In9.Cu" signal "IN3")
		(22 "In10.Cu" signal "GND4")
		(24 "In11.Cu" signal "IN4")
		(26 "In12.Cu" signal "GND5")
		(28 "In13.Cu" signal "IN5")
		(30 "In14.Cu" signal "GND6")
		(32 "In15.Cu" signal "IN6")
		(34 "In16.Cu" signal "GND7")
		(2 "B.Cu" signal "BOTTOM")
		(9 "F.Adhes" user "F.Adhesive")
		(11 "B.Adhes" user "B.Adhesive")
		(13 "F.Paste" user "Package Geometry/Pastemask Top")
		(15 "B.Paste" user "Package Geometry/Pastemask Bottom")
		(5 "F.SilkS" user "Ref Des/Silkscreen Top")
		(7 "B.SilkS" user "Ref Des/Silkscreen Bottom")
		(1 "F.Mask" user "Board Geometry/Soldermask Top")
		(3 "B.Mask" user "Board Geometry/Soldermask Bottom")
		(17 "Dwgs.User" user "User.Drawings")
		(19 "Cmts.User" user "User.Comments")
		(21 "Eco1.User" user "User.Eco1")
		(23 "Eco2.User" user "User.Eco2")
		(25 "Edge.Cuts" user "Board Geometry/Outline")
		(27 "Margin" user)
		(31 "F.CrtYd" user "Package Geometry/Place Bound Top")
		(29 "B.CrtYd" user "Package Geometry/Place Bound Bottom")
		(35 "F.Fab" user "Ref Des/Assembly Top")
		(33 "B.Fab" user "Ref Des/Assembly Bottom")
	)
	(footprint ""
		(layer "F.Cu")
		(at 48.202088 -350.098614 90)
		(property "Reference" "C2179"
			(at 0 0 90)
			(layer "F.SilkS")
			(hide yes)
			(effects
				(font
					(size 1.27 1.27)
				)
			)
		)
		(property "Value" ""
			(at 0 0 90)
			(layer "F.Fab")
			(effects
				(font
					(size 1.27 1.27)
				)
			)
		)
		(duplicate_pad_numbers_are_jumpers no)
		(fp_line
			(start 0.299974 -0.150114)
			(end 0.299974 0.150114)
			(stroke
				(width 0.1)
				(type default)
			)
			(layer "F.Fab")
		)
		(fp_line
			(start -0.299974 -0.150114)
			(end 0.299974 -0.150114)
			(stroke
				(width 0.1)
				(type default)
			)
			(layer "F.Fab")
		)
		(fp_line
			(start 0.299974 0.150114)
			(end -0.299974 0.150114)
			(stroke
				(width 0.1)
				(type default)
			)
			(layer "F.Fab")
		)
		(fp_line
			(start -0.299974 0.150114)
			(end -0.299974 -0.150114)
			(stroke
				(width 0.1)
				(type default)
			)
			(layer "F.Fab")
		)
		(pad "1" smd rect
			(at -0.2667 0 90)
			(size 0.3048 0.381)
			(layers "F.Cu" "F.Mask" "F.Paste")
			(net "P5E_PEX0_STN4_TX_DN<66>")
		)
		(pad "2" smd rect
			(at 0.2667 0 90)
			(size 0.3048 0.381)
			(layers "F.Cu" "F.Mask" "F.Paste")
			(net "P5E_PEX0_STN4_TX_C_DN<66>")
		)
	)
	(footprint ""
		(layer "F.Cu")
		(at 256.992628 -257.148838 -90)
		(property "Reference" "R1396"
			(at 0 0 270)
			(layer "F.SilkS")
			(hide yes)
			(effects
				(font
					(size 1.27 1.27)
				)
			)
		)
		(property "Value" ""
			(at 0 0 270)
			(layer "F.Fab")
			(effects
				(font
					(size 1.27 1.27)
				)
			)
		)
		(duplicate_pad_numbers_are_jumpers no)
		(fp_line
			(start -0.7874 0.4064)
			(end -0.7874 -0.4064)
			(stroke
				(width 0.1524)
				(type default)
			)
			(layer "F.SilkS")
		)
		(fp_line
			(start 0.7874 0.4064)
			(end -0.7874 0.4064)
			(stroke
				(width 0.1524)
				(type default)
			)
			(layer "F.SilkS")
		)
		(fp_line
			(start -0.7874 -0.4064)
			(end 0.7874 -0.4064)
			(stroke
				(width 0.1524)
				(type default)
			)
			(layer "F.SilkS")
		)
		(fp_line
			(start 0.7874 -0.4064)
			(end 0.7874 0.4064)
			(stroke
				(width 0.1524)
				(type default)
			)
			(layer "F.SilkS")
		)
		(fp_line
			(start -0.67945 0.3048)
			(end -0.67945 -0.305054)
			(stroke
				(width 0.1)
				(type default)
			)
			(layer "F.Fab")
		)
		(fp_line
			(start -0.12065 0.3048)
			(end -0.67945 0.3048)
			(stroke
				(width 0.1)
				(type default)
			)
			(layer "F.Fab")
		)
		(fp_line
			(start 0.120396 0.3048)
			(end 0.120396 0.2794)
			(stroke
				(width 0.1)
				(type default)
			)
			(layer "F.Fab")
		)
		(fp_line
			(start 0.67945 0.3048)
			(end 0.120396 0.3048)
			(stroke
				(width 0.1)
				(type default)
			)
			(layer "F.Fab")
		)
		(fp_line
			(start -0.12065 0.2794)
			(end -0.12065 0.3048)
			(stroke
				(width 0.1)
				(type default)
			)
			(layer "F.Fab")
		)
		(fp_line
			(start 0.120396 0.2794)
			(end -0.12065 0.2794)
			(stroke
				(width 0.1)
				(type default)
			)
			(layer "F.Fab")
		)
		(fp_line
			(start -0.12065 -0.2794)
			(end 0.12065 -0.2794)
			(stroke
				(width 0.1)
				(type default)
			)
			(layer "F.Fab")
		)
		(fp_line
			(start 0.12065 -0.2794)
			(end 0.12065 -0.3048)
			(stroke
				(width 0.1)
				(type default)
			)
			(layer "F.Fab")
		)
		(fp_line
			(start 0.12065 -0.3048)
			(end 0.67945 -0.3048)
			(stroke
				(width 0.1)
				(type default)
			)
			(layer "F.Fab")
		)
		(fp_line
			(start 0.67945 -0.3048)
			(end 0.67945 0.3048)
			(stroke
				(width 0.1)
				(type default)
			)
			(layer "F.Fab")
		)
		(fp_line
			(start -0.67945 -0.305054)
			(end -0.12065 -0.305054)
			(stroke
				(width 0.1)
				(type default)
			)
			(layer "F.Fab")
		)
		(fp_line
			(start -0.12065 -0.305054)
			(end -0.12065 -0.2794)
			(stroke
				(width 0.1)
				(type default)
			)
			(layer "F.Fab")
		)
		(pad "1" smd circle
			(at -0.40005 0 270)
			(size 0 0)
			(layers "F.Cu" "F.Mask" "F.Paste")
			(net "P3V3_LED")
		)
		(pad "2" smd circle
			(at 0.40005 0 270)
			(size 0 0)
			(layers "F.Cu" "F.Mask" "F.Paste")
			(net "LED_PEX2_SYS_ERR_N")
		)
	)
	(footprint ""
		(layer "F.Cu")
		(at 104.267762 -55.083456)
		(property "Reference" "PC373"
			(at 0 0 0)
			(layer "F.SilkS")
			(hide yes)
			(effects
				(font
					(size 1.27 1.27)
				)
			)
		)
		(property "Value" ""
			(at 0 0 0)
			(layer "F.Fab")
			(effects
				(font
					(size 1.27 1.27)
				)
			)
		)
		(duplicate_pad_numbers_are_jumpers no)
		(fp_line
			(start -0.7874 -0.4064)
			(end 0.7874 -0.4064)
			(stroke
				(width 0.1524)
				(type default)
			)
			(layer "F.SilkS")
		)
		(fp_line
			(start -0.7874 0.4064)
			(end -0.7874 -0.4064)
			(stroke
				(width 0.1524)
				(type default)
			)
			(layer "F.SilkS")
		)
		(fp_line
			(start 0.7874 -0.4064)
			(end 0.7874 0.4064)
			(stroke
				(width 0.1524)
				(type default)
			)
			(layer "F.SilkS")
		)
		(fp_line
			(start 0.7874 0.4064)
			(end -0.7874 0.4064)
			(stroke
				(width 0.1524)
				(type default)
			)
			(layer "F.SilkS")
		)
		(fp_line
			(start -0.67945 -0.305054)
			(end -0.12065 -0.305054)
			(stroke
				(width 0.1)
				(type default)
			)
			(layer "F.Fab")
		)
		(fp_line
			(start -0.67945 0.3048)
			(end -0.67945 -0.305054)
			(stroke
				(width 0.1)
				(type default)
			)
			(layer "F.Fab")
		)
		(fp_line
			(start -0.12065 -0.305054)
			(end -0.12065 -0.2794)
			(stroke
				(width 0.1)
				(type default)
			)
			(layer "F.Fab")
		)
		(fp_line
			(start -0.12065 -0.2794)
			(end 0.12065 -0.2794)
			(stroke
				(width 0.1)
				(type default)
			)
			(layer "F.Fab")
		)
		(fp_line
			(start -0.12065 0.2794)
			(end -0.12065 0.3048)
			(stroke
				(width 0.1)
				(type default)
			)
			(layer "F.Fab")
		)
		(fp_line
			(start -0.12065 0.3048)
			(end -0.67945 0.3048)
			(stroke
				(width 0.1)
				(type default)
			)
			(layer "F.Fab")
		)
		(fp_line
			(start 0.120396 0.2794)
			(end -0.12065 0.2794)
			(stroke
				(width 0.1)
				(type default)
			)
			(layer "F.Fab")
		)
		(fp_line
			(start 0.120396 0.3048)
			(end 0.120396 0.2794)
			(stroke
				(width 0.1)
				(type default)
			)
			(layer "F.Fab")
		)
		(fp_line
			(start 0.12065 -0.3048)
			(end 0.67945 -0.3048)
			(stroke
				(width 0.1)
				(type default)
			)
			(layer "F.Fab")
		)
		(fp_line
			(start 0.12065 -0.2794)
			(end 0.12065 -0.3048)
			(stroke
				(width 0.1)
				(type default)
			)
			(layer "F.Fab")
		)
		(fp_line
			(start 0.67945 -0.3048)
			(end 0.67945 0.3048)
			(stroke
				(width 0.1)
				(type default)
			)
			(layer "F.Fab")
		)
		(fp_line
			(start 0.67945 0.3048)
			(end 0.120396 0.3048)
			(stroke
				(width 0.1)
				(type default)
			)
			(layer "F.Fab")
		)
		(pad "1" smd circle
			(at -0.40005 0)
			(size 0 0)
			(layers "F.Cu" "F.Mask" "F.Paste")
			(net "P5V_AUX")
		)
		(pad "2" smd circle
			(at 0.40005 0)
			(size 0 0)
			(layers "F.Cu" "F.Mask" "F.Paste")
			(net "GND")
		)
	)
	(footprint ""
		(layer "F.Cu")
		(at 30.081982 -283.389832 180)
		(property "Reference" "C3062"
			(at 0 0 180)
			(layer "F.SilkS")
			(hide yes)
			(effects
				(font
					(size 1.27 1.27)
				)
			)
		)
		(property "Value" ""
			(at 0 0 180)
			(layer "F.Fab")
			(effects
				(font
					(size 1.27 1.27)
				)
			)
		)
		(duplicate_pad_numbers_are_jumpers no)
		(fp_line
			(start 1.2954 0.5842)
			(end -1.2954 0.5842)
			(stroke
				(width 0.1524)
				(type default)
			)
			(layer "F.SilkS")
		)
		(fp_line
			(start 1.2954 -0.5842)
			(end 1.2954 0.5842)
			(stroke
				(width 0.1524)
				(type default)
			)
			(layer "F.SilkS")
		)
		(fp_line
			(start -1.2954 0.5842)
			(end -1.2954 -0.5842)
			(stroke
				(width 0.1524)
				(type default)
			)
			(layer "F.SilkS")
		)
		(fp_line
			(start -1.2954 -0.5842)
			(end 1.2954 -0.5842)
			(stroke
				(width 0.1524)
				(type default)
			)
			(layer "F.SilkS")
		)
		(fp_line
			(start 1.1938 0.4064)
			(end 0.8636 0.4064)
			(stroke
				(width 0.1)
				(type default)
			)
			(layer "F.Fab")
		)
		(fp_line
			(start 1.1938 -0.4064)
			(end 1.1938 0.4064)
			(stroke
				(width 0.1)
				(type default)
			)
			(layer "F.Fab")
		)
		(fp_line
			(start 0.8636 0.4572)
			(end -0.8636 0.4572)
			(stroke
				(width 0.1)
				(type default)
			)
			(layer "F.Fab")
		)
		(fp_line
			(start 0.8636 0.4064)
			(end 0.8636 0.4572)
			(stroke
				(width 0.1)
				(type default)
			)
			(layer "F.Fab")
		)
		(fp_line
			(start 0.8636 -0.4064)
			(end 1.1938 -0.4064)
			(stroke
				(width 0.1)
				(type default)
			)
			(layer "F.Fab")
		)
		(fp_line
			(start 0.8636 -0.4572)
			(end 0.8636 -0.4064)
			(stroke
				(width 0.1)
				(type default)
			)
			(layer "F.Fab")
		)
		(fp_line
			(start -0.8636 0.4572)
			(end -0.8636 0.4064)
			(stroke
				(width 0.1)
				(type default)
			)
			(layer "F.Fab")
		)
		(fp_line
			(start -0.8636 0.4064)
			(end -1.1938 0.4064)
			(stroke
				(width 0.1)
				(type default)
			)
			(layer "F.Fab")
		)
		(fp_line
			(start -0.8636 -0.4064)
			(end -0.8636 -0.4572)
			(stroke
				(width 0.1)
				(type default)
			)
			(layer "F.Fab")
		)
		(fp_line
			(start -0.8636 -0.4572)
			(end 0.8636 -0.4572)
			(stroke
				(width 0.1)
				(type default)
			)
			(layer "F.Fab")
		)
		(fp_line
			(start -1.1938 0.4064)
			(end -1.1938 -0.4064)
			(stroke
				(width 0.1)
				(type default)
			)
			(layer "F.Fab")
		)
		(fp_line
			(start -1.1938 -0.4064)
			(end -0.8636 -0.4064)
			(stroke
				(width 0.1)
				(type default)
			)
			(layer "F.Fab")
		)
		(pad "1" smd rect
			(at -0.7366 0 90)
			(size 0.7112 0.8128)
			(layers "F.Cu" "F.Mask" "F.Paste")
			(net "PCEPLL7_VDDA18_PEX0_R")
		)
		(pad "2" smd rect
			(at 0.7366 0 90)
			(size 0.7112 0.8128)
			(layers "F.Cu" "F.Mask" "F.Paste")
			(net "GND")
		)
	)
	(footprint ""
		(layer "F.Cu")
		(at 327.533 -219.329 180)
		(property "Reference" "R4161"
			(at 0 0 180)
			(layer "F.SilkS")
			(hide yes)
			(effects
				(font
					(size 1.27 1.27)
				)
			)
		)
		(property "Value" ""
			(at 0 0 180)
			(layer "F.Fab")
			(effects
				(font
					(size 1.27 1.27)
				)
			)
		)
		(duplicate_pad_numbers_are_jumpers no)
		(fp_line
			(start 0.7874 0.4064)
			(end -0.7874 0.4064)
			(stroke
				(width 0.1524)
				(type default)
			)
			(layer "F.SilkS")
		)
		(fp_line
			(start 0.7874 -0.4064)
			(end 0.7874 0.4064)
			(stroke
				(width 0.1524)
				(type default)
			)
			(layer "F.SilkS")
		)
		(fp_line
			(start -0.7874 0.4064)
			(end -0.7874 -0.4064)
			(stroke
				(width 0.1524)
				(type default)
			)
			(layer "F.SilkS")
		)
		(fp_line
			(start -0.7874 -0.4064)
			(end 0.7874 -0.4064)
			(stroke
				(width 0.1524)
				(type default)
			)
			(layer "F.SilkS")
		)
		(fp_line
			(start 0.67945 0.3048)
			(end 0.120396 0.3048)
			(stroke
				(width 0.1)
				(type default)
			)
			(layer "F.Fab")
		)
		(fp_line
			(start 0.67945 -0.3048)
			(end 0.67945 0.3048)
			(stroke
				(width 0.1)
				(type default)
			)
			(layer "F.Fab")
		)
		(fp_line
			(start 0.12065 -0.2794)
			(end 0.12065 -0.3048)
			(stroke
				(width 0.1)
				(type default)
			)
			(layer "F.Fab")
		)
		(fp_line
			(start 0.12065 -0.3048)
			(end 0.67945 -0.3048)
			(stroke
				(width 0.1)
				(type default)
			)
			(layer "F.Fab")
		)
		(fp_line
			(start 0.120396 0.3048)
			(end 0.120396 0.2794)
			(stroke
				(width 0.1)
				(type default)
			)
			(layer "F.Fab")
		)
		(fp_line
			(start 0.120396 0.2794)
			(end -0.12065 0.2794)
			(stroke
				(width 0.1)
				(type default)
			)
			(layer "F.Fab")
		)
		(fp_line
			(start -0.12065 0.3048)
			(end -0.67945 0.3048)
			(stroke
				(width 0.1)
				(type default)
			)
			(layer "F.Fab")
		)
		(fp_line
			(start -0.12065 0.2794)
			(end -0.12065 0.3048)
			(stroke
				(width 0.1)
				(type default)
			)
			(layer "F.Fab")
		)
		(fp_line
			(start -0.12065 -0.2794)
			(end 0.12065 -0.2794)
			(stroke
				(width 0.1)
				(type default)
			)
			(layer "F.Fab")
		)
		(fp_line
			(start -0.12065 -0.305054)
			(end -0.12065 -0.2794)
			(stroke
				(width 0.1)
				(type default)
			)
			(layer "F.Fab")
		)
		(fp_line
			(start -0.67945 0.3048)
			(end -0.67945 -0.305054)
			(stroke
				(width 0.1)
				(type default)
			)
			(layer "F.Fab")
		)
		(fp_line
			(start -0.67945 -0.305054)
			(end -0.12065 -0.305054)
			(stroke
				(width 0.1)
				(type default)
			)
			(layer "F.Fab")
		)
		(pad "1" smd circle
			(at -0.40005 0 180)
			(size 0 0)
			(layers "F.Cu" "F.Mask" "F.Paste")
			(net "PRSNT_SSD14_FPGA_N")
		)
		(pad "2" smd circle
			(at 0.40005 0 180)
			(size 0 0)
			(layers "F.Cu" "F.Mask" "F.Paste")
			(net "PRSNT_SSD14_FPGA_R_N")
		)
	)
)
